# BASEBOARD_FAB2 (Tioga Pass) — schematic netlist excerpt (pin names and nets, part order shuffled) for the footprints in the layout excerpt that follows; sources: Cadence DE-HDL packaged netlist, KiCad conversion of Wiwynn_Tioga_Pass_MB.brd

C3A6  CAP_A  47UF 4V 20% X5R  pkg 0603V  page 228 : A = PVDDQ_KLM ; B = GND
C3G3  CAP  10UF 4V 20% X6S  pkg 0603LF  page 233 : A = PVPP_GHJ ; B = GND
R25W185  RES  4.75K 1% CHIP  pkg 0402  page 255 : A = P3V3_STBY ; B = BMC_JTAG_SEL

(kicad_pcb
	(version 20260206)
	(generator "pcbnew")
	(generator_version "10.0")
	(general
		(thickness 1.6)
		(legacy_teardrops no)
	)
	(paper "A4")
	(title_block
		(title "Wiwynn_Tioga_Pass_MB.brd")
		(comment 1 "Tioga Pass / footprints 1628-1630 of 4770")
	)
	(layers
		(0 "F.Cu" signal "TOP")
		(4 "In1.Cu" signal "L2GND")
		(6 "In2.Cu" signal "L3")
		(8 "In3.Cu" signal "L4GND")
		(10 "In4.Cu" signal "L5")
		(12 "In5.Cu" signal "L6GND")
		(14 "In6.Cu" signal "L7VCC")
		(16 "In7.Cu" signal "L8VCC")
		(18 "In8.Cu" signal "L9GND")
		(20 "In9.Cu" signal "L10")
		(22 "In10.Cu" signal "L11GND")
		(24 "In11.Cu" signal "L12")
		(26 "In12.Cu" signal "L13GND")
		(2 "B.Cu" signal "BOTTOM")
		(9 "F.Adhes" user "F.Adhesive")
		(11 "B.Adhes" user "B.Adhesive")
		(13 "F.Paste" user "Package Geometry/Pastemask Top")
		(15 "B.Paste" user "Package Geometry/Pastemask Bottom")
		(5 "F.SilkS" user "Ref Des/Silkscreen Top")
		(7 "B.SilkS" user "Ref Des/Silkscreen Bottom")
		(1 "F.Mask" user "Board Geometry/Soldermask Top")
		(3 "B.Mask" user "Board Geometry/Soldermask Bottom")
		(17 "Dwgs.User" user "User.Drawings")
		(19 "Cmts.User" user "User.Comments")
		(21 "Eco1.User" user "User.Eco1")
		(23 "Eco2.User" user "User.Eco2")
		(25 "Edge.Cuts" user "Board Geometry/Outline")
		(27 "Margin" user)
		(31 "F.CrtYd" user "Package Geometry/Place Bound Top")
		(29 "B.CrtYd" user "Package Geometry/Place Bound Bottom")
		(35 "F.Fab" user "Ref Des/Assembly Top")
		(33 "B.Fab" user "Ref Des/Assembly Bottom")
	)
	(footprint ""
		(layer "F.Cu")
		(at 153.543 -12.954 -90)
		(property "Reference" "C3G3"
			(at 0 0 270)
			(layer "F.SilkS")
			(hide yes)
			(effects
				(font
					(size 1.27 1.27)
				)
			)
		)
		(property "Value" ""
			(at 0 0 270)
			(layer "F.Fab")
			(effects
				(font
					(size 1.27 1.27)
				)
			)
		)
		(duplicate_pad_numbers_are_jumpers no)
		(fp_poly
			(pts
				(xy -0.4953 -0.2032) (xy 0.4953 -0.2032) (xy 0.4953 1.6002) (xy -0.4953 1.6002)
			)
			(stroke
				(width 0)
				(type default)
			)
			(fill no)
			(layer "F.CrtYd")
		)
		(fp_line
			(start -0.4953 1.6002)
			(end -0.4953 -0.2032)
			(stroke
				(width 0.1)
				(type default)
			)
			(layer "F.Fab")
		)
		(fp_line
			(start 0.4953 1.6002)
			(end -0.4953 1.6002)
			(stroke
				(width 0.1)
				(type default)
			)
			(layer "F.Fab")
		)
		(fp_line
			(start -0.4953 -0.2032)
			(end 0.4953 -0.2032)
			(stroke
				(width 0.1)
				(type default)
			)
			(layer "F.Fab")
		)
		(fp_line
			(start 0.4953 -0.2032)
			(end 0.4953 1.6002)
			(stroke
				(width 0.1)
				(type default)
			)
			(layer "F.Fab")
		)
		(pad "1" smd rect
			(at 0 0 270)
			(size 0.762 0.889)
			(layers "F.Cu" "F.Mask" "F.Paste")
			(net "PVPP_GHJ")
		)
		(pad "2" smd rect
			(at 0 1.397 270)
			(size 0.762 0.889)
			(layers "F.Cu" "F.Mask" "F.Paste")
			(net "GND")
		)
		(zone
			(layer "F.Cu")
			(hatch none 0.5)
			(connect_pads
				(clearance 0)
			)
			(min_thickness 0.25)
			(keepout
				(tracks not_allowed)
				(vias allowed)
				(pads allowed)
				(copperpour not_allowed)
				(footprints allowed)
			)
			(placement
				(enabled no)
				(sheetname "")
			)
			(fill
				(thermal_gap 0.5)
				(thermal_bridge_width 0.5)
				(island_removal_mode 0)
			)
			(polygon
				(pts
					(xy 153.0985 -13.335) (xy 153.0985 -12.573) (xy 152.5905 -12.573) (xy 152.5905 -13.335)
				)
			)
		)
	)
	(footprint ""
		(layer "F.Cu")
		(at 452.312024 -146.55546)
		(property "Reference" "R25W185"
			(at -0.8382 -0.67818 0)
			(unlocked yes)
			(layer "F.SilkS")
			(effects
				(font
					(size 0.4064 0.254)
					(thickness 0.1524)
				)
				(justify left)
			)
		)
		(property "Value" ""
			(at 0 0 0)
			(layer "F.Fab")
			(effects
				(font
					(size 1.27 1.27)
				)
			)
		)
		(duplicate_pad_numbers_are_jumpers no)
		(fp_poly
			(pts
				(xy -0.2794 -0.1016) (xy 0.2794 -0.1016) (xy 0.2794 0.9906) (xy -0.2794 0.9906)
			)
			(stroke
				(width 0)
				(type default)
			)
			(fill no)
			(layer "F.CrtYd")
		)
		(fp_line
			(start -0.2794 -0.1016)
			(end -0.2794 0.9906)
			(stroke
				(width 0.1)
				(type default)
			)
			(layer "F.Fab")
		)
		(fp_line
			(start -0.2794 0.9906)
			(end 0.2794 0.9906)
			(stroke
				(width 0.1)
				(type default)
			)
			(layer "F.Fab")
		)
		(fp_line
			(start 0.2794 -0.1016)
			(end -0.2794 -0.1016)
			(stroke
				(width 0.1)
				(type default)
			)
			(layer "F.Fab")
		)
		(fp_line
			(start 0.2794 0.9906)
			(end 0.2794 -0.1016)
			(stroke
				(width 0.1)
				(type default)
			)
			(layer "F.Fab")
		)
		(pad "1" smd rect
			(at 0 0)
			(size 0.508 0.508)
			(layers "F.Cu" "F.Mask" "F.Paste")
			(net "P3V3_STBY")
		)
		(pad "2" smd rect
			(at 0 0.889)
			(size 0.508 0.508)
			(layers "F.Cu" "F.Mask" "F.Paste")
			(net "BMC_JTAG_SEL")
		)
		(zone
			(layer "F.Cu")
			(hatch none 0.5)
			(connect_pads
				(clearance 0)
			)
			(min_thickness 0.25)
			(keepout
				(tracks allowed)
				(vias not_allowed)
				(pads allowed)
				(copperpour not_allowed)
				(footprints allowed)
			)
			(placement
				(enabled no)
				(sheetname "")
			)
			(fill
				(thermal_gap 0.5)
				(thermal_bridge_width 0.5)
				(island_removal_mode 0)
			)
			(polygon
				(pts
					(xy 452.058024 -146.30146) (xy 452.566024 -146.30146) (xy 452.566024 -145.92046) (xy 452.058024 -145.92046)
				)
			)
		)
		(zone
			(layer "F.Cu")
			(hatch none 0.5)
			(connect_pads
				(clearance 0)
			)
			(min_thickness 0.25)
			(keepout
				(tracks not_allowed)
				(vias allowed)
				(pads allowed)
				(copperpour not_allowed)
				(footprints allowed)
			)
			(placement
				(enabled no)
				(sheetname "")
			)
			(fill
				(thermal_gap 0.5)
				(thermal_bridge_width 0.5)
				(island_removal_mode 0)
			)
			(polygon
				(pts
					(xy 452.058024 -145.92046) (xy 452.566024 -145.92046) (xy 452.566024 -146.30146) (xy 452.058024 -146.30146)
				)
			)
		)
	)
	(footprint ""
		(layer "F.Cu")
		(at 111.000032 -140.208 90)
		(property "Reference" "C3A6"
			(at 1.848866 0.752348 90)
			(unlocked yes)
			(layer "F.SilkS")
			(effects
				(font
					(size 1.27 0.9652)
					(thickness 0.1524)
				)
			)
		)
		(property "Value" ""
			(at 0 0 90)
			(layer "F.Fab")
			(effects
				(font
					(size 1.27 1.27)
				)
			)
		)
		(duplicate_pad_numbers_are_jumpers no)
		(fp_rect
			(start -0.500126 1.598422)
			(end 0.500126 -0.201422)
			(stroke
				(width 0)
				(type default)
			)
			(fill no)
			(layer "F.CrtYd")
		)
		(fp_line
			(start 0.500126 -0.201422)
			(end 0.500126 1.598422)
			(stroke
				(width 0.1)
				(type default)
			)
			(layer "F.Fab")
		)
		(fp_line
			(start -0.500126 -0.201422)
			(end 0.500126 -0.201422)
			(stroke
				(width 0.1)
				(type default)
			)
			(layer "F.Fab")
		)
		(fp_line
			(start 0.500126 1.598422)
			(end -0.500126 1.598422)
			(stroke
				(width 0.1)
				(type default)
			)
			(layer "F.Fab")
		)
		(fp_line
			(start -0.500126 1.598422)
			(end -0.500126 -0.201422)
			(stroke
				(width 0.1)
				(type default)
			)
			(layer "F.Fab")
		)
		(pad "1" smd rect
			(at 0 0)
			(size 0.889 0.9906)
			(layers "F.Cu" "F.Mask" "F.Paste")
			(net "PVDDQ_KLM")
		)
		(pad "2" smd rect
			(at 0 1.397)
			(size 0.889 0.9906)
			(layers "F.Cu" "F.Mask" "F.Paste")
			(net "GND")
		)
		(zone
			(layer "F.Cu")
			(hatch none 0.5)
			(connect_pads
				(clearance 0)
			)
			(min_thickness 0.25)
			(keepout
				(tracks allowed)
				(vias not_allowed)
				(pads allowed)
				(copperpour not_allowed)
				(footprints allowed)
			)
			(placement
				(enabled no)
				(sheetname "")
			)
			(fill
				(thermal_gap 0.5)
				(thermal_bridge_width 0.5)
				(island_removal_mode 0)
			)
			(polygon
				(pts
					(xy 111.952532 -139.7127) (xy 111.952532 -140.7033) (xy 111.444532 -140.7033) (xy 111.444532 -139.7127)
				)
			)
		)
		(zone
			(layer "F.Cu")
			(hatch none 0.5)
			(connect_pads
				(clearance 0)
			)
			(min_thickness 0.25)
			(keepout
				(tracks not_allowed)
				(vias allowed)
				(pads allowed)
				(copperpour not_allowed)
				(footprints allowed)
			)
			(placement
				(enabled no)
				(sheetname "")
			)
			(fill
				(thermal_gap 0.5)
				(thermal_bridge_width 0.5)
				(island_removal_mode 0)
			)
			(polygon
				(pts
					(xy 111.952532 -139.7127) (xy 111.952532 -140.7033) (xy 111.444532 -140.7033) (xy 111.444532 -139.7127)
				)
			)
		)
	)
)
